# TIMECARD (Time Appliance Project (Time Card)) — schematic netlist excerpt (pin names and nets, part order shuffled) for the footprints in the layout excerpt that follows; sources: Cadence DE-HDL packaged netlist, KiCad conversion of R4006-B0001-02_R01.brd

R171  RESISTOR  4.7KOHM 1%  pkg SMC_0402R_H016  page 25 : \1\ = SG ; \2\ = FPGA_IO_0
C60  CAPACITOR  0.1UF 25V 10%  pkg SMC_0402R_H022  page 21 : \1\ = XP5R0V_MAC ; \2\ = SG

(kicad_pcb
	(version 20260206)
	(generator "pcbnew")
	(generator_version "10.0")
	(general
		(thickness 1.6)
		(legacy_teardrops no)
	)
	(paper "A4")
	(title_block
		(title "timecard-production-celestica-r4006 — R4006-B0001-02_R01.brd")
		(comment 1 "Time Appliance Project (Time Card) / footprints 942-943 of 1113")
	)
	(layers
		(0 "F.Cu" signal "TOP")
		(4 "In1.Cu" signal "L02_GND1")
		(6 "In2.Cu" signal "L03_SIG1")
		(8 "In3.Cu" signal "L04_GND2")
		(10 "In4.Cu" signal "L05_VCC1")
		(12 "In5.Cu" signal "L06_VCC2")
		(14 "In6.Cu" signal "L07_GND3")
		(16 "In7.Cu" signal "L08_SIG2")
		(18 "In8.Cu" signal "L09_GND4")
		(2 "B.Cu" signal "BOTTOM")
		(9 "F.Adhes" user "F.Adhesive")
		(11 "B.Adhes" user "B.Adhesive")
		(13 "F.Paste" user "Package Geometry/Pastemask Top")
		(15 "B.Paste" user "Package Geometry/Pastemask Bottom")
		(5 "F.SilkS" user "Ref Des/Silkscreen Top")
		(7 "B.SilkS" user "Ref Des/Silkscreen Bottom")
		(1 "F.Mask" user "Board Geometry/Soldermask Top")
		(3 "B.Mask" user "Board Geometry/Soldermask Bottom")
		(17 "Dwgs.User" user "User.Drawings")
		(19 "Cmts.User" user "User.Comments")
		(21 "Eco1.User" user "User.Eco1")
		(23 "Eco2.User" user "User.Eco2")
		(25 "Edge.Cuts" user "Board Geometry/Outline")
		(27 "Margin" user)
		(31 "F.CrtYd" user "Package Geometry/Place Bound Top")
		(29 "B.CrtYd" user "Package Geometry/Place Bound Bottom")
		(35 "F.Fab" user "Ref Des/Assembly Top")
		(33 "B.Fab" user "Ref Des/Assembly Bottom")
	)
	(footprint ""
		(layer "B.Cu")
		(at 101.0412 -64.2874 90)
		(property "Reference" "R171"
			(at 3.4036 -0.24257 270)
			(unlocked yes)
			(layer "B.SilkS")
			(effects
				(font
					(size 0.7874 0.5842)
					(thickness 0.1524)
				)
				(justify mirror)
			)
		)
		(property "Value" "VAL*"
			(at -0.02032 2.13233 90)
			(unlocked yes)
			(layer "B.Fab")
			(hide yes)
			(effects
				(font
					(size 0.7874 0.5842)
					(thickness 0.1524)
				)
				(justify mirror)
			)
		)
		(property "Tolerance" "TOL*"
			(at -0.044704 3.05435 90)
			(unlocked yes)
			(layer "Cmts.User")
			(hide yes)
			(effects
				(font
					(size 0.7874 0.5842)
					(thickness 0.1524)
				)
				(justify mirror)
			)
		)
		(property "User Part Number" "PARTNUM*"
			(at -0.02032 4.024884 90)
			(unlocked yes)
			(layer "Cmts.User")
			(hide yes)
			(effects
				(font
					(size 0.7874 0.5842)
					(thickness 0.1524)
				)
				(justify mirror)
			)
		)
		(property "Device Type" "RESISTOR-G155-14701-01,4.7KOHMA"
			(at -0.008382 1.210564 90)
			(unlocked yes)
			(layer "B.Fab")
			(hide yes)
			(effects
				(font
					(size 0.7874 0.5842)
					(thickness 0.1524)
				)
				(justify mirror)
			)
		)
		(duplicate_pad_numbers_are_jumpers no)
		(fp_line
			(start 1.143 -0.5588)
			(end 1.143 0.5588)
			(stroke
				(width 0.1)
				(type default)
			)
			(layer "B.SilkS")
		)
		(fp_line
			(start -1.143 -0.5588)
			(end 1.143 -0.5588)
			(stroke
				(width 0.1)
				(type default)
			)
			(layer "B.SilkS")
		)
		(fp_line
			(start 1.143 0.5588)
			(end -1.143 0.5588)
			(stroke
				(width 0.1)
				(type default)
			)
			(layer "B.SilkS")
		)
		(fp_line
			(start -1.143 0.5588)
			(end -1.143 -0.5588)
			(stroke
				(width 0.1)
				(type default)
			)
			(layer "B.SilkS")
		)
		(fp_rect
			(start -1.143 0.5588)
			(end 1.143 -0.5588)
			(stroke
				(width 0)
				(type default)
			)
			(fill no)
			(layer "B.CrtYd")
		)
		(fp_line
			(start 0.508 -0.3048)
			(end 0.508 0.3048)
			(stroke
				(width 0.1)
				(type default)
			)
			(layer "B.Fab")
		)
		(fp_line
			(start -0.508 -0.3048)
			(end 0.508 -0.3048)
			(stroke
				(width 0.1)
				(type default)
			)
			(layer "B.Fab")
		)
		(fp_line
			(start 0.508 0.3048)
			(end -0.508 0.3048)
			(stroke
				(width 0.1)
				(type default)
			)
			(layer "B.Fab")
		)
		(fp_line
			(start -0.508 0.3048)
			(end -0.508 -0.3048)
			(stroke
				(width 0.1)
				(type default)
			)
			(layer "B.Fab")
		)
		(pad "1" smd rect
			(at 0.5334 0 270)
			(size 0.7112 0.6096)
			(layers "B.Cu" "B.Mask" "B.Paste")
			(net "SG")
		)
		(pad "2" smd rect
			(at -0.5334 0 270)
			(size 0.7112 0.6096)
			(layers "B.Cu" "B.Mask" "B.Paste")
			(net "FPGA_IO_0")
		)
		(zone
			(layer "B.Cu")
			(hatch none 0.5)
			(connect_pads
				(clearance 0)
			)
			(min_thickness 0.25)
			(keepout
				(tracks allowed)
				(vias not_allowed)
				(pads allowed)
				(copperpour not_allowed)
				(footprints allowed)
			)
			(placement
				(enabled no)
				(sheetname "")
			)
			(fill
				(thermal_gap 0.5)
				(thermal_bridge_width 0.5)
				(island_removal_mode 0)
			)
			(polygon
				(pts
					(xy 101.346 -64.2112) (xy 101.346 -64.3636) (xy 100.7364 -64.3636) (xy 100.7364 -64.2112)
				)
			)
		)
	)
	(footprint ""
		(layer "B.Cu")
		(at 73.66 -72.771 -90)
		(property "Reference" "C60"
			(at -3.81 -0.59563 270)
			(unlocked yes)
			(layer "B.SilkS")
			(effects
				(font
					(size 0.7874 0.5842)
					(thickness 0.1524)
				)
				(justify mirror)
			)
		)
		(property "Value" "VAL*"
			(at -0.0762 2.067306 270)
			(unlocked yes)
			(layer "B.Fab")
			(hide yes)
			(effects
				(font
					(size 0.7874 0.5842)
					(thickness 0.1524)
				)
				(justify mirror)
			)
		)
		(property "Tolerance" "TOL*"
			(at -0.0762 3.032506 270)
			(unlocked yes)
			(layer "Cmts.User")
			(hide yes)
			(effects
				(font
					(size 0.7874 0.5842)
					(thickness 0.1524)
				)
				(justify mirror)
			)
		)
		(property "User Part Number" "PARTNUM*"
			(at -0.1016 4.023106 270)
			(unlocked yes)
			(layer "Cmts.User")
			(hide yes)
			(effects
				(font
					(size 0.7874 0.5842)
					(thickness 0.1524)
				)
				(justify mirror)
			)
		)
		(property "Device Type" "CAPACITOR-G105-0B104-EK,0.1UF,A"
			(at -0.0508 1.127506 270)
			(unlocked yes)
			(layer "B.Fab")
			(hide yes)
			(effects
				(font
					(size 0.7874 0.5842)
					(thickness 0.1524)
				)
				(justify mirror)
			)
		)
		(duplicate_pad_numbers_are_jumpers no)
		(fp_line
			(start -1.143 0.5588)
			(end -1.143 -0.5588)
			(stroke
				(width 0.1)
				(type default)
			)
			(layer "B.SilkS")
		)
		(fp_line
			(start 1.143 0.5588)
			(end -1.143 0.5588)
			(stroke
				(width 0.1)
				(type default)
			)
			(layer "B.SilkS")
		)
		(fp_line
			(start -1.143 -0.5588)
			(end 1.143 -0.5588)
			(stroke
				(width 0.1)
				(type default)
			)
			(layer "B.SilkS")
		)
		(fp_line
			(start 1.143 -0.5588)
			(end 1.143 0.5588)
			(stroke
				(width 0.1)
				(type default)
			)
			(layer "B.SilkS")
		)
		(fp_rect
			(start 1.143 -0.5588)
			(end -1.143 0.5588)
			(stroke
				(width 0)
				(type default)
			)
			(fill no)
			(layer "B.CrtYd")
		)
		(fp_line
			(start -0.508 0.3048)
			(end -0.508 -0.3048)
			(stroke
				(width 0.1)
				(type default)
			)
			(layer "B.Fab")
		)
		(fp_line
			(start 0.508 0.3048)
			(end -0.508 0.3048)
			(stroke
				(width 0.1)
				(type default)
			)
			(layer "B.Fab")
		)
		(fp_line
			(start -0.508 -0.3048)
			(end 0.508 -0.3048)
			(stroke
				(width 0.1)
				(type default)
			)
			(layer "B.Fab")
		)
		(fp_line
			(start 0.508 -0.3048)
			(end 0.508 0.3048)
			(stroke
				(width 0.1)
				(type default)
			)
			(layer "B.Fab")
		)
		(pad "1" smd rect
			(at 0.5334 0 90)
			(size 0.7112 0.6096)
			(layers "B.Cu" "B.Mask" "B.Paste")
			(net "XP5R0V_MAC")
		)
		(pad "2" smd rect
			(at -0.5334 0 90)
			(size 0.7112 0.6096)
			(layers "B.Cu" "B.Mask" "B.Paste")
			(net "SG")
		)
		(zone
			(layer "B.Cu")
			(hatch none 0.5)
			(connect_pads
				(clearance 0)
			)
			(min_thickness 0.25)
			(keepout
				(tracks allowed)
				(vias not_allowed)
				(pads allowed)
				(copperpour not_allowed)
				(footprints allowed)
			)
			(placement
				(enabled no)
				(sheetname "")
			)
			(fill
				(thermal_gap 0.5)
				(thermal_bridge_width 0.5)
				(island_removal_mode 0)
			)
			(polygon
				(pts
					(xy 73.9648 -72.6948) (xy 73.9648 -72.8472) (xy 73.3552 -72.8472) (xy 73.3552 -72.6948)
				)
			)
		)
	)
)
